G04 #@! TF.GenerationSoftware,KiCad,Pcbnew,(5.0.1)-3*
G04 #@! TF.CreationDate,2019-04-10T15:36:06+02:00*
G04 #@! TF.ProjectId,discovery,646973636F766572792E6B696361645F,rev?*
G04 #@! TF.SameCoordinates,PX4c4640PY8a48028*
G04 #@! TF.FileFunction,Legend,Top*
G04 #@! TF.FilePolarity,Positive*
%FSLAX46Y46*%
G04 Gerber Fmt 4.6, Leading zero omitted, Abs format (unit mm)*
%MOMM*%
%LPD*%
G01*
G04 APERTURE LIST*
%ADD10C,0.400000*%
%ADD11C,0.300000*%
%ADD12C,1.000000*%
%ADD13C,0.100000*%
%ADD14C,0.120000*%
%ADD15C,0.150000*%
G04 APERTURE END LIST*
D10*
X20060302Y19379730D02*
X20060302Y17855920D01*
X19298398Y18617825D02*
X20822207Y18617825D01*
X19298398Y15855920D02*
X19298398Y16998778D01*
X19298398Y16427349D02*
X21298398Y16427349D01*
X21012683Y16617825D01*
X20822207Y16808301D01*
X20726969Y16998778D01*
X21107921Y15094016D02*
X21203160Y14998778D01*
X21298398Y14808301D01*
X21298398Y14332111D01*
X21203160Y14141635D01*
X21107921Y14046397D01*
X20917445Y13951159D01*
X20726969Y13951159D01*
X20441255Y14046397D01*
X19298398Y15189254D01*
X19298398Y13951159D01*
X21298398Y13379730D02*
X19298398Y12713063D01*
X21298398Y12046397D01*
X15762662Y19379730D02*
X15762662Y17855920D01*
X15000758Y18617825D02*
X16524567Y18617825D01*
X15000758Y15855920D02*
X15000758Y16998778D01*
X15000758Y16427349D02*
X17000758Y16427349D01*
X16715043Y16617825D01*
X16524567Y16808301D01*
X16429329Y16998778D01*
X16810281Y15094016D02*
X16905520Y14998778D01*
X17000758Y14808301D01*
X17000758Y14332111D01*
X16905520Y14141635D01*
X16810281Y14046397D01*
X16619805Y13951159D01*
X16429329Y13951159D01*
X16143615Y14046397D01*
X15000758Y15189254D01*
X15000758Y13951159D01*
X17000758Y13379730D02*
X15000758Y12713063D01*
X17000758Y12046397D01*
X20803177Y41135711D02*
X20803177Y42659520D01*
X21565081Y41897616D02*
X20041272Y41897616D01*
X21565081Y44659520D02*
X21565081Y43516663D01*
X21565081Y44088092D02*
X19565081Y44088092D01*
X19850796Y43897616D01*
X20041272Y43707140D01*
X20136510Y43516663D01*
X19755558Y45421425D02*
X19660320Y45516663D01*
X19565081Y45707140D01*
X19565081Y46183330D01*
X19660320Y46373806D01*
X19755558Y46469044D01*
X19946034Y46564282D01*
X20136510Y46564282D01*
X20422224Y46469044D01*
X21565081Y45326187D01*
X21565081Y46564282D01*
X19565081Y47135711D02*
X21565081Y47802378D01*
X19565081Y48469044D01*
X15107302Y48168090D02*
X15107302Y46644280D01*
X14345398Y47406185D02*
X15869207Y47406185D01*
X14345398Y44644280D02*
X14345398Y45787138D01*
X14345398Y45215709D02*
X16345398Y45215709D01*
X16059683Y45406185D01*
X15869207Y45596661D01*
X15773969Y45787138D01*
X16154921Y43882376D02*
X16250160Y43787138D01*
X16345398Y43596661D01*
X16345398Y43120471D01*
X16250160Y42929995D01*
X16154921Y42834757D01*
X15964445Y42739519D01*
X15773969Y42739519D01*
X15488255Y42834757D01*
X14345398Y43977614D01*
X14345398Y42739519D01*
X16345398Y42168090D02*
X14345398Y41501423D01*
X16345398Y40834757D01*
X36591817Y71365551D02*
X36591817Y72889360D01*
X37353721Y72127456D02*
X35829912Y72127456D01*
X37353721Y74889360D02*
X37353721Y73746503D01*
X37353721Y74317932D02*
X35353721Y74317932D01*
X35639436Y74127456D01*
X35829912Y73936980D01*
X35925150Y73746503D01*
X35544198Y75651265D02*
X35448960Y75746503D01*
X35353721Y75936980D01*
X35353721Y76413170D01*
X35448960Y76603646D01*
X35544198Y76698884D01*
X35734674Y76794122D01*
X35925150Y76794122D01*
X36210864Y76698884D01*
X37353721Y75556027D01*
X37353721Y76794122D01*
X35353721Y77365551D02*
X37353721Y78032218D01*
X35353721Y78698884D01*
X-4503Y68527071D02*
X-4503Y70050880D01*
X757401Y69288976D02*
X-766408Y69288976D01*
X757401Y72050880D02*
X757401Y70908023D01*
X757401Y71479452D02*
X-1242599Y71479452D01*
X-956884Y71288976D01*
X-766408Y71098500D01*
X-671170Y70908023D01*
X-1052122Y72812785D02*
X-1147360Y72908023D01*
X-1242599Y73098500D01*
X-1242599Y73574690D01*
X-1147360Y73765166D01*
X-1052122Y73860404D01*
X-861646Y73955642D01*
X-671170Y73955642D01*
X-385456Y73860404D01*
X757401Y72717547D01*
X757401Y73955642D01*
X-1242599Y74527071D02*
X757401Y75193738D01*
X-1242599Y75860404D01*
D11*
X34758960Y80905320D02*
X34758960Y64847440D01*
X1487440Y81530160D02*
X1487440Y64222600D01*
X22321320Y50130680D02*
X22321320Y39162960D01*
X13686520Y38776880D02*
X13686520Y50653920D01*
X13995400Y9800560D02*
X13995400Y21906200D01*
X22060840Y9800560D02*
X22060840Y21906200D01*
D12*
X125101280Y43940821D02*
X124910803Y43559869D01*
X124910803Y42988440D01*
X125101280Y42417012D01*
X125482232Y42036060D01*
X125863184Y41845583D01*
X126625089Y41655107D01*
X127196518Y41655107D01*
X127958422Y41845583D01*
X128339375Y42036060D01*
X128720327Y42417012D01*
X128910803Y42988440D01*
X128910803Y43369393D01*
X128720327Y43940821D01*
X128529851Y44131298D01*
X127196518Y44131298D01*
X127196518Y43369393D01*
X128910803Y45845583D02*
X124910803Y45845583D01*
X128910803Y48131298D01*
X124910803Y48131298D01*
X128910803Y50036060D02*
X124910803Y50036060D01*
X124910803Y50988440D01*
X125101280Y51559869D01*
X125482232Y51940821D01*
X125863184Y52131298D01*
X126625089Y52321774D01*
X127196518Y52321774D01*
X127958422Y52131298D01*
X128339375Y51940821D01*
X128720327Y51559869D01*
X128910803Y50988440D01*
X128910803Y50036060D01*
X65786994Y36300821D02*
X65786994Y39348440D01*
X67310803Y37824631D02*
X64263184Y37824631D01*
X67310803Y43348440D02*
X67310803Y41062726D01*
X67310803Y42205583D02*
X63310803Y42205583D01*
X63882232Y41824631D01*
X64263184Y41443679D01*
X64453660Y41062726D01*
X63691756Y44872250D02*
X63501280Y45062726D01*
X63310803Y45443679D01*
X63310803Y46396060D01*
X63501280Y46777012D01*
X63691756Y46967488D01*
X64072708Y47157964D01*
X64453660Y47157964D01*
X65025089Y46967488D01*
X67310803Y44681774D01*
X67310803Y47157964D01*
X63310803Y48300821D02*
X67310803Y49634155D01*
X63310803Y50967488D01*
D10*
X25180919Y1555248D02*
X25180919Y4055248D01*
X26133300Y4055248D01*
X26371396Y3936200D01*
X26490443Y3817153D01*
X26609491Y3579058D01*
X26609491Y3221915D01*
X26490443Y2983820D01*
X26371396Y2864772D01*
X26133300Y2745724D01*
X25180919Y2745724D01*
X29109491Y1793343D02*
X28990443Y1674296D01*
X28633300Y1555248D01*
X28395205Y1555248D01*
X28038062Y1674296D01*
X27799967Y1912391D01*
X27680919Y2150486D01*
X27561872Y2626677D01*
X27561872Y2983820D01*
X27680919Y3460010D01*
X27799967Y3698105D01*
X28038062Y3936200D01*
X28395205Y4055248D01*
X28633300Y4055248D01*
X28990443Y3936200D01*
X29109491Y3817153D01*
X30180920Y1555248D02*
X30180920Y4055248D01*
X5450200Y1638888D02*
X5450200Y4138888D01*
X6402580Y4138888D01*
X6640676Y4019840D01*
X6759723Y3900793D01*
X6878771Y3662698D01*
X6878771Y3305555D01*
X6759723Y3067460D01*
X6640676Y2948412D01*
X6402580Y2829364D01*
X5450200Y2829364D01*
X9378771Y1876983D02*
X9259723Y1757936D01*
X8902580Y1638888D01*
X8664485Y1638888D01*
X8307342Y1757936D01*
X8069247Y1996031D01*
X7950200Y2234126D01*
X7831152Y2710317D01*
X7831152Y3067460D01*
X7950200Y3543650D01*
X8069247Y3781745D01*
X8307342Y4019840D01*
X8664485Y4138888D01*
X8902580Y4138888D01*
X9259723Y4019840D01*
X9378771Y3900793D01*
X10450200Y1638888D02*
X10450200Y4138888D01*
X25160599Y30483128D02*
X25160599Y32983128D01*
X26112980Y32983128D01*
X26351076Y32864080D01*
X26470123Y32745033D01*
X26589171Y32506938D01*
X26589171Y32149795D01*
X26470123Y31911700D01*
X26351076Y31792652D01*
X26112980Y31673604D01*
X25160599Y31673604D01*
X29089171Y30721223D02*
X28970123Y30602176D01*
X28612980Y30483128D01*
X28374885Y30483128D01*
X28017742Y30602176D01*
X27779647Y30840271D01*
X27660599Y31078366D01*
X27541552Y31554557D01*
X27541552Y31911700D01*
X27660599Y32387890D01*
X27779647Y32625985D01*
X28017742Y32864080D01*
X28374885Y32983128D01*
X28612980Y32983128D01*
X28970123Y32864080D01*
X29089171Y32745033D01*
X30160600Y30483128D02*
X30160600Y32983128D01*
X5160640Y30432328D02*
X5160640Y32932328D01*
X6113020Y32932328D01*
X6351116Y32813280D01*
X6470163Y32694233D01*
X6589211Y32456138D01*
X6589211Y32098995D01*
X6470163Y31860900D01*
X6351116Y31741852D01*
X6113020Y31622804D01*
X5160640Y31622804D01*
X9089211Y30670423D02*
X8970163Y30551376D01*
X8613020Y30432328D01*
X8374925Y30432328D01*
X8017782Y30551376D01*
X7779687Y30789471D01*
X7660640Y31027566D01*
X7541592Y31503757D01*
X7541592Y31860900D01*
X7660640Y32337090D01*
X7779687Y32575185D01*
X8017782Y32813280D01*
X8374925Y32932328D01*
X8613020Y32932328D01*
X8970163Y32813280D01*
X9089211Y32694233D01*
X10160640Y30432328D02*
X10160640Y32932328D01*
X26363977Y84152646D02*
X26483024Y84033599D01*
X26602072Y83676456D01*
X26602072Y83438360D01*
X26483024Y83081218D01*
X26244929Y82843122D01*
X26006834Y82724075D01*
X25530643Y82605027D01*
X25173500Y82605027D01*
X24697310Y82724075D01*
X24459215Y82843122D01*
X24221120Y83081218D01*
X24102072Y83438360D01*
X24102072Y83676456D01*
X24221120Y84033599D01*
X24340167Y84152646D01*
X26602072Y85224075D02*
X24102072Y85224075D01*
X24102072Y86176456D01*
X24221120Y86414551D01*
X24340167Y86533599D01*
X24578262Y86652646D01*
X24935405Y86652646D01*
X25173500Y86533599D01*
X25292548Y86414551D01*
X25411596Y86176456D01*
X25411596Y85224075D01*
X24102072Y87724075D02*
X26125881Y87724075D01*
X26363977Y87843122D01*
X26483024Y87962170D01*
X26602072Y88200265D01*
X26602072Y88676456D01*
X26483024Y88914551D01*
X26363977Y89033599D01*
X26125881Y89152646D01*
X24102072Y89152646D01*
X12145057Y84000246D02*
X12264104Y83881199D01*
X12383152Y83524056D01*
X12383152Y83285960D01*
X12264104Y82928818D01*
X12026009Y82690722D01*
X11787914Y82571675D01*
X11311723Y82452627D01*
X10954580Y82452627D01*
X10478390Y82571675D01*
X10240295Y82690722D01*
X10002200Y82928818D01*
X9883152Y83285960D01*
X9883152Y83524056D01*
X10002200Y83881199D01*
X10121247Y84000246D01*
X12383152Y85071675D02*
X9883152Y85071675D01*
X9883152Y86024056D01*
X10002200Y86262151D01*
X10121247Y86381199D01*
X10359342Y86500246D01*
X10716485Y86500246D01*
X10954580Y86381199D01*
X11073628Y86262151D01*
X11192676Y86024056D01*
X11192676Y85071675D01*
X9883152Y87571675D02*
X11906961Y87571675D01*
X12145057Y87690722D01*
X12264104Y87809770D01*
X12383152Y88047865D01*
X12383152Y88524056D01*
X12264104Y88762151D01*
X12145057Y88881199D01*
X11906961Y89000246D01*
X9883152Y89000246D01*
D13*
G04 #@! TO.C,J2*
X32601280Y37698440D02*
X32601280Y51498440D01*
X23001280Y37698440D02*
X32601280Y37698440D01*
X23001280Y51498440D02*
X23001280Y37698440D01*
X32601280Y51498440D02*
X23001280Y51498440D01*
X33401280Y43598440D02*
X32601280Y43598440D01*
X33401280Y45598440D02*
X33401280Y43598440D01*
X32601280Y45598440D02*
X33401280Y45598440D01*
G04 #@! TO.C,J4*
X3401280Y43598440D02*
X2601280Y43598440D01*
X2601280Y43598440D02*
X2601280Y45598440D01*
X2601280Y45598440D02*
X3401280Y45598440D01*
X3401280Y37698440D02*
X13001280Y37698440D01*
X13001280Y37698440D02*
X13001280Y51498440D01*
X13001280Y51498440D02*
X3401280Y51498440D01*
X3401280Y51498440D02*
X3401280Y37698440D01*
G04 #@! TO.C,J5*
X3401280Y22665840D02*
X3401280Y8865840D01*
X13001280Y22665840D02*
X3401280Y22665840D01*
X13001280Y8865840D02*
X13001280Y22665840D01*
X3401280Y8865840D02*
X13001280Y8865840D01*
X2601280Y16765840D02*
X3401280Y16765840D01*
X2601280Y14765840D02*
X2601280Y16765840D01*
X3401280Y14765840D02*
X2601280Y14765840D01*
G04 #@! TO.C,J6*
X32601280Y16765840D02*
X33401280Y16765840D01*
X33401280Y16765840D02*
X33401280Y14765840D01*
X33401280Y14765840D02*
X32601280Y14765840D01*
X32601280Y22665840D02*
X23001280Y22665840D01*
X23001280Y22665840D02*
X23001280Y8865840D01*
X23001280Y8865840D02*
X32601280Y8865840D01*
X32601280Y8865840D02*
X32601280Y22665840D01*
G04 #@! TO.C,J1*
X2001280Y73898440D02*
X3401280Y73898440D01*
X2001280Y71898440D02*
X2001280Y73898440D01*
X2001280Y71898440D02*
X3401280Y71898440D01*
X3401280Y63698440D02*
X3401280Y81698440D01*
X13001280Y81698440D02*
X3401280Y81698440D01*
X13001280Y63698440D02*
X13001280Y81698440D01*
X13001280Y63698440D02*
X3401280Y63698440D01*
G04 #@! TO.C,J3*
X23001280Y81698440D02*
X32601280Y81698440D01*
X23001280Y81698440D02*
X23001280Y63698440D01*
X23001280Y63698440D02*
X32601280Y63698440D01*
X32601280Y81698440D02*
X32601280Y63698440D01*
X34001280Y73498440D02*
X32601280Y73498440D01*
X34001280Y73498440D02*
X34001280Y71498440D01*
X34001280Y71498440D02*
X32601280Y71498440D01*
D14*
G04 #@! TO.C,W1*
X142751280Y-1560D02*
G75*
G03X142751280Y-1560I-2750000J0D01*
G01*
G04 #@! TO.C,W2*
X2751280Y89998440D02*
G75*
G03X2751280Y89998440I-2750000J0D01*
G01*
G04 #@! TO.C,W3*
X142751280Y89998440D02*
G75*
G03X142751280Y89998440I-2750000J0D01*
G01*
G04 #@! TO.C,W4*
X2751280Y-1560D02*
G75*
G03X2751280Y-1560I-2750000J0D01*
G01*
G04 #@! TO.C,J2*
D15*
X33070860Y50098307D02*
X33785146Y50098307D01*
X33928003Y50050688D01*
X34023241Y49955450D01*
X34070860Y49812593D01*
X34070860Y49717355D01*
X33166099Y50526879D02*
X33118480Y50574498D01*
X33070860Y50669736D01*
X33070860Y50907831D01*
X33118480Y51003069D01*
X33166099Y51050688D01*
X33261337Y51098307D01*
X33356575Y51098307D01*
X33499432Y51050688D01*
X34070860Y50479260D01*
X34070860Y51098307D01*
G04 #@! TO.C,J4*
X2078740Y50081827D02*
X2793026Y50081827D01*
X2935883Y50034208D01*
X3031121Y49938970D01*
X3078740Y49796113D01*
X3078740Y49700875D01*
X2412074Y50986589D02*
X3078740Y50986589D01*
X2031121Y50748494D02*
X2745407Y50510399D01*
X2745407Y51129446D01*
G04 #@! TO.C,J5*
X2033020Y21278227D02*
X2747306Y21278227D01*
X2890163Y21230608D01*
X2985401Y21135370D01*
X3033020Y20992513D01*
X3033020Y20897275D01*
X2033020Y22230608D02*
X2033020Y21754418D01*
X2509211Y21706799D01*
X2461592Y21754418D01*
X2413973Y21849656D01*
X2413973Y22087751D01*
X2461592Y22182989D01*
X2509211Y22230608D01*
X2604449Y22278227D01*
X2842544Y22278227D01*
X2937782Y22230608D01*
X2985401Y22182989D01*
X3033020Y22087751D01*
X3033020Y21849656D01*
X2985401Y21754418D01*
X2937782Y21706799D01*
G04 #@! TO.C,J6*
X32995620Y21311427D02*
X33709906Y21311427D01*
X33852763Y21263808D01*
X33948001Y21168570D01*
X33995620Y21025713D01*
X33995620Y20930475D01*
X32995620Y22216189D02*
X32995620Y22025713D01*
X33043240Y21930475D01*
X33090859Y21882856D01*
X33233716Y21787618D01*
X33424192Y21739999D01*
X33805144Y21739999D01*
X33900382Y21787618D01*
X33948001Y21835237D01*
X33995620Y21930475D01*
X33995620Y22120951D01*
X33948001Y22216189D01*
X33900382Y22263808D01*
X33805144Y22311427D01*
X33567049Y22311427D01*
X33471811Y22263808D01*
X33424192Y22216189D01*
X33376573Y22120951D01*
X33376573Y21930475D01*
X33424192Y21835237D01*
X33471811Y21787618D01*
X33567049Y21739999D01*
G04 #@! TO.C,J1*
X13530620Y80367867D02*
X14244906Y80367867D01*
X14387763Y80320248D01*
X14483001Y80225010D01*
X14530620Y80082153D01*
X14530620Y79986915D01*
X14530620Y81367867D02*
X14530620Y80796439D01*
X14530620Y81082153D02*
X13530620Y81082153D01*
X13673478Y80986915D01*
X13768716Y80891677D01*
X13816335Y80796439D01*
G04 #@! TO.C,J3*
X21483380Y80272907D02*
X22197666Y80272907D01*
X22340523Y80225288D01*
X22435761Y80130050D01*
X22483380Y79987193D01*
X22483380Y79891955D01*
X21483380Y80653860D02*
X21483380Y81272907D01*
X21864333Y80939574D01*
X21864333Y81082431D01*
X21911952Y81177669D01*
X21959571Y81225288D01*
X22054809Y81272907D01*
X22292904Y81272907D01*
X22388142Y81225288D01*
X22435761Y81177669D01*
X22483380Y81082431D01*
X22483380Y80796717D01*
X22435761Y80701479D01*
X22388142Y80653860D01*
G04 #@! TO.C,W1*
X142915298Y-1746180D02*
X143153393Y-2746180D01*
X143343869Y-2031895D01*
X143534345Y-2746180D01*
X143772440Y-1746180D01*
X144677202Y-2746180D02*
X144105774Y-2746180D01*
X144391488Y-2746180D02*
X144391488Y-1746180D01*
X144296250Y-1889038D01*
X144201012Y-1984276D01*
X144105774Y-2031895D01*
G04 #@! TO.C,W2*
X3260838Y90875100D02*
X3498933Y89875100D01*
X3689409Y90589385D01*
X3879885Y89875100D01*
X4117980Y90875100D01*
X4451314Y90779861D02*
X4498933Y90827480D01*
X4594171Y90875100D01*
X4832266Y90875100D01*
X4927504Y90827480D01*
X4975123Y90779861D01*
X5022742Y90684623D01*
X5022742Y90589385D01*
X4975123Y90446528D01*
X4403695Y89875100D01*
X5022742Y89875100D01*
G04 #@! TO.C,W3*
X142915298Y88253820D02*
X143153393Y87253820D01*
X143343869Y87968105D01*
X143534345Y87253820D01*
X143772440Y88253820D01*
X144058155Y88253820D02*
X144677202Y88253820D01*
X144343869Y87872867D01*
X144486726Y87872867D01*
X144581964Y87825248D01*
X144629583Y87777629D01*
X144677202Y87682391D01*
X144677202Y87444296D01*
X144629583Y87349058D01*
X144581964Y87301439D01*
X144486726Y87253820D01*
X144201012Y87253820D01*
X144105774Y87301439D01*
X144058155Y87349058D01*
G04 #@! TO.C,W4*
X2915298Y-1746180D02*
X3153393Y-2746180D01*
X3343869Y-2031895D01*
X3534345Y-2746180D01*
X3772440Y-1746180D01*
X4581964Y-2079514D02*
X4581964Y-2746180D01*
X4343869Y-1698561D02*
X4105774Y-2412847D01*
X4724821Y-2412847D01*
G04 #@! TO.C,W5*
X49664218Y86013660D02*
X49902313Y85013660D01*
X50092789Y85727945D01*
X50283265Y85013660D01*
X50521360Y86013660D01*
X51378503Y86013660D02*
X50902313Y86013660D01*
X50854694Y85537469D01*
X50902313Y85585088D01*
X50997551Y85632707D01*
X51235646Y85632707D01*
X51330884Y85585088D01*
X51378503Y85537469D01*
X51426122Y85442231D01*
X51426122Y85204136D01*
X51378503Y85108898D01*
X51330884Y85061279D01*
X51235646Y85013660D01*
X50997551Y85013660D01*
X50902313Y85061279D01*
X50854694Y85108898D01*
G04 #@! TO.C,W6*
X49664218Y63513660D02*
X49902313Y62513660D01*
X50092789Y63227945D01*
X50283265Y62513660D01*
X50521360Y63513660D01*
X51330884Y63513660D02*
X51140408Y63513660D01*
X51045170Y63466040D01*
X50997551Y63418421D01*
X50902313Y63275564D01*
X50854694Y63085088D01*
X50854694Y62704136D01*
X50902313Y62608898D01*
X50949932Y62561279D01*
X51045170Y62513660D01*
X51235646Y62513660D01*
X51330884Y62561279D01*
X51378503Y62608898D01*
X51426122Y62704136D01*
X51426122Y62942231D01*
X51378503Y63037469D01*
X51330884Y63085088D01*
X51235646Y63132707D01*
X51045170Y63132707D01*
X50949932Y63085088D01*
X50902313Y63037469D01*
X50854694Y62942231D01*
G04 #@! TO.C,W7*
X49664218Y41013660D02*
X49902313Y40013660D01*
X50092789Y40727945D01*
X50283265Y40013660D01*
X50521360Y41013660D01*
X50807075Y41013660D02*
X51473741Y41013660D01*
X51045170Y40013660D01*
G04 #@! TO.C,W8*
X49664218Y18513660D02*
X49902313Y17513660D01*
X50092789Y18227945D01*
X50283265Y17513660D01*
X50521360Y18513660D01*
X51045170Y18085088D02*
X50949932Y18132707D01*
X50902313Y18180326D01*
X50854694Y18275564D01*
X50854694Y18323183D01*
X50902313Y18418421D01*
X50949932Y18466040D01*
X51045170Y18513660D01*
X51235646Y18513660D01*
X51330884Y18466040D01*
X51378503Y18418421D01*
X51426122Y18323183D01*
X51426122Y18275564D01*
X51378503Y18180326D01*
X51330884Y18132707D01*
X51235646Y18085088D01*
X51045170Y18085088D01*
X50949932Y18037469D01*
X50902313Y17989850D01*
X50854694Y17894612D01*
X50854694Y17704136D01*
X50902313Y17608898D01*
X50949932Y17561279D01*
X51045170Y17513660D01*
X51235646Y17513660D01*
X51330884Y17561279D01*
X51378503Y17608898D01*
X51426122Y17704136D01*
X51426122Y17894612D01*
X51378503Y17989850D01*
X51330884Y18037469D01*
X51235646Y18085088D01*
G04 #@! TO.C,W9*
X109664218Y88763660D02*
X109902313Y87763660D01*
X110092789Y88477945D01*
X110283265Y87763660D01*
X110521360Y88763660D01*
X110949932Y87763660D02*
X111140408Y87763660D01*
X111235646Y87811279D01*
X111283265Y87858898D01*
X111378503Y88001755D01*
X111426122Y88192231D01*
X111426122Y88573183D01*
X111378503Y88668421D01*
X111330884Y88716040D01*
X111235646Y88763660D01*
X111045170Y88763660D01*
X110949932Y88716040D01*
X110902313Y88668421D01*
X110854694Y88573183D01*
X110854694Y88335088D01*
X110902313Y88239850D01*
X110949932Y88192231D01*
X111045170Y88144612D01*
X111235646Y88144612D01*
X111330884Y88192231D01*
X111378503Y88239850D01*
X111426122Y88335088D01*
G04 #@! TO.C,W10*
X109188027Y66263660D02*
X109426122Y65263660D01*
X109616599Y65977945D01*
X109807075Y65263660D01*
X110045170Y66263660D01*
X110949932Y65263660D02*
X110378503Y65263660D01*
X110664218Y65263660D02*
X110664218Y66263660D01*
X110568980Y66120802D01*
X110473741Y66025564D01*
X110378503Y65977945D01*
X111568980Y66263660D02*
X111664218Y66263660D01*
X111759456Y66216040D01*
X111807075Y66168421D01*
X111854694Y66073183D01*
X111902313Y65882707D01*
X111902313Y65644612D01*
X111854694Y65454136D01*
X111807075Y65358898D01*
X111759456Y65311279D01*
X111664218Y65263660D01*
X111568980Y65263660D01*
X111473741Y65311279D01*
X111426122Y65358898D01*
X111378503Y65454136D01*
X111330884Y65644612D01*
X111330884Y65882707D01*
X111378503Y66073183D01*
X111426122Y66168421D01*
X111473741Y66216040D01*
X111568980Y66263660D01*
G04 #@! TO.C,W11*
X109188027Y21263660D02*
X109426122Y20263660D01*
X109616599Y20977945D01*
X109807075Y20263660D01*
X110045170Y21263660D01*
X110949932Y20263660D02*
X110378503Y20263660D01*
X110664218Y20263660D02*
X110664218Y21263660D01*
X110568980Y21120802D01*
X110473741Y21025564D01*
X110378503Y20977945D01*
X111902313Y20263660D02*
X111330884Y20263660D01*
X111616599Y20263660D02*
X111616599Y21263660D01*
X111521360Y21120802D01*
X111426122Y21025564D01*
X111330884Y20977945D01*
G04 #@! TO.C,W12*
X109188027Y43763660D02*
X109426122Y42763660D01*
X109616599Y43477945D01*
X109807075Y42763660D01*
X110045170Y43763660D01*
X110949932Y42763660D02*
X110378503Y42763660D01*
X110664218Y42763660D02*
X110664218Y43763660D01*
X110568980Y43620802D01*
X110473741Y43525564D01*
X110378503Y43477945D01*
X111330884Y43668421D02*
X111378503Y43716040D01*
X111473741Y43763660D01*
X111711837Y43763660D01*
X111807075Y43716040D01*
X111854694Y43668421D01*
X111902313Y43573183D01*
X111902313Y43477945D01*
X111854694Y43335088D01*
X111283265Y42763660D01*
X111902313Y42763660D01*
G04 #@! TD*
M02*
